(kicad_pcb
	(version 20260206)
	(generator "pcbnew")
	(generator_version "10.0")
	(general
		(thickness 1.6)
		(legacy_teardrops no)
	)
	(paper "A4")
	(title_block
		(title "Bryce Canyon_R.DPB_16317-1_OCP.brd")
		(comment 1 "Bryce Canyon / footprints 947-953 of 2099")
	)
	(layers
		(0 "F.Cu" signal "TOP")
		(4 "In1.Cu" signal "L2GND")
		(6 "In2.Cu" signal "L3")
		(8 "In3.Cu" signal "L4VCC")
		(10 "In4.Cu" signal "L5VCC")
		(12 "In5.Cu" signal "L6")
		(14 "In6.Cu" signal "L7GND")
		(2 "B.Cu" signal "BOTTOM")
		(9 "F.Adhes" user "F.Adhesive")
		(11 "B.Adhes" user "B.Adhesive")
		(13 "F.Paste" user "Package Geometry/Pastemask Top")
		(15 "B.Paste" user "Package Geometry/Pastemask Bottom")
		(5 "F.SilkS" user "Ref Des/Silkscreen Top")
		(7 "B.SilkS" user "Ref Des/Silkscreen Bottom")
		(1 "F.Mask" user "Board Geometry/Soldermask Top")
		(3 "B.Mask" user "Board Geometry/Soldermask Bottom")
		(17 "Dwgs.User" user "User.Drawings")
		(19 "Cmts.User" user "User.Comments")
		(21 "Eco1.User" user "User.Eco1")
		(23 "Eco2.User" user "User.Eco2")
		(25 "Edge.Cuts" user "Board Geometry/Outline")
		(27 "Margin" user)
		(31 "F.CrtYd" user "Package Geometry/Place Bound Top")
		(29 "B.CrtYd" user "Package Geometry/Place Bound Bottom")
		(35 "F.Fab" user "Ref Des/Assembly Top")
		(33 "B.Fab" user "Ref Des/Assembly Bottom")
	)
	(footprint ""
		(layer "F.Cu")
		(at 320.7004 -146.6342 180)
		(property "Reference" "R484"
			(at 0 0 180)
			(layer "F.SilkS")
			(hide yes)
			(effects
				(font
					(size 1.27 1.27)
				)
			)
		)
		(property "Value" "10KR2F-2-GP"
			(at 0.064008 -3.993896 180)
			(unlocked yes)
			(layer "F.Fab")
			(hide yes)
			(effects
				(font
					(size 1.016 1.016)
					(thickness 0.1524)
				)
			)
		)
		(property "Device Type" "R402H16"
			(at 0.064008 -5.517896 180)
			(unlocked yes)
			(layer "F.Fab")
			(hide yes)
			(effects
				(font
					(size 1.016 1.016)
					(thickness 0.1524)
				)
			)
		)
		(duplicate_pad_numbers_are_jumpers no)
		(fp_line
			(start 0.508 -0.9398)
			(end -0.508 -0.9398)
			(stroke
				(width 0.1524)
				(type default)
			)
			(layer "F.SilkS")
		)
		(fp_line
			(start -0.508 -0.9398)
			(end -0.508 0.9398)
			(stroke
				(width 0.1524)
				(type default)
			)
			(layer "F.SilkS")
		)
		(fp_rect
			(start -0.508 0.9398)
			(end 0.508 -0.9398)
			(stroke
				(width 0)
				(type default)
			)
			(fill no)
			(layer "F.CrtYd")
		)
		(fp_rect
			(start -0.508 0.9398)
			(end 0.508 -0.9398)
			(stroke
				(width 0)
				(type default)
			)
			(fill no)
			(layer "F.Fab")
		)
		(pad "1" smd custom
			(at 0 -0.4445 180)
			(size 0.1397 0.1397)
			(layers "F.Cu" "F.Mask" "F.Paste")
			(net "P3V3_STBY_B")
			(options
				(clearance outline)
				(anchor circle)
			)
			(primitives
				(gr_poly
					(pts
						(arc
							(start -0.1778 -0.2794)
							(mid -0.249642 -0.249642)
							(end -0.2794 -0.1778)
						)
						(arc
							(start -0.2794 0.1778)
							(mid -0.249642 0.249642)
							(end -0.1778 0.2794)
						)
						(arc
							(start 0.1778 0.2794)
							(mid 0.249642 0.249642)
							(end 0.2794 0.1778)
						)
						(arc
							(start 0.2794 -0.1778)
							(mid 0.249642 -0.249642)
							(end 0.1778 -0.2794)
						)
					)
					(width 0)
					(fill yes)
				)
			)
		)
		(pad "2" smd custom
			(at 0 0.4445 180)
			(size 0.1397 0.1397)
			(layers "F.Cu" "F.Mask" "F.Paste")
			(net "HDD_PRSNT_18")
			(options
				(clearance outline)
				(anchor circle)
			)
			(primitives
				(gr_poly
					(pts
						(arc
							(start -0.1778 -0.2794)
							(mid -0.249642 -0.249642)
							(end -0.2794 -0.1778)
						)
						(arc
							(start -0.2794 0.1778)
							(mid -0.249642 0.249642)
							(end -0.1778 0.2794)
						)
						(arc
							(start 0.1778 0.2794)
							(mid 0.249642 0.249642)
							(end 0.2794 0.1778)
						)
						(arc
							(start 0.2794 -0.1778)
							(mid 0.249642 -0.249642)
							(end 0.1778 -0.2794)
						)
					)
					(width 0)
					(fill yes)
				)
			)
		)
	)
	(footprint ""
		(layer "F.Cu")
		(at 333.248 -128.651 180)
		(property "Reference" "R492"
			(at 0 0 180)
			(layer "F.SilkS")
			(hide yes)
			(effects
				(font
					(size 1.27 1.27)
				)
			)
		)
		(property "Value" "1KR2F-3-GP"
			(at 0.064008 -3.993896 180)
			(unlocked yes)
			(layer "F.Fab")
			(hide yes)
			(effects
				(font
					(size 1.016 1.016)
					(thickness 0.1524)
				)
			)
		)
		(property "Device Type" "R402H16"
			(at 0.064008 -5.517896 180)
			(unlocked yes)
			(layer "F.Fab")
			(hide yes)
			(effects
				(font
					(size 1.016 1.016)
					(thickness 0.1524)
				)
			)
		)
		(duplicate_pad_numbers_are_jumpers no)
		(fp_line
			(start 0.508 -0.9398)
			(end -0.508 -0.9398)
			(stroke
				(width 0.1524)
				(type default)
			)
			(layer "F.SilkS")
		)
		(fp_line
			(start -0.508 -0.9398)
			(end -0.508 0.9398)
			(stroke
				(width 0.1524)
				(type default)
			)
			(layer "F.SilkS")
		)
		(fp_rect
			(start -0.508 0.9398)
			(end 0.508 -0.9398)
			(stroke
				(width 0)
				(type default)
			)
			(fill no)
			(layer "F.CrtYd")
		)
		(fp_rect
			(start -0.508 0.9398)
			(end 0.508 -0.9398)
			(stroke
				(width 0)
				(type default)
			)
			(fill no)
			(layer "F.Fab")
		)
		(pad "1" smd custom
			(at 0 -0.4445 180)
			(size 0.1397 0.1397)
			(layers "F.Cu" "F.Mask" "F.Paste")
			(net "P3V3_STBY_B")
			(options
				(clearance outline)
				(anchor circle)
			)
			(primitives
				(gr_poly
					(pts
						(arc
							(start -0.1778 -0.2794)
							(mid -0.249642 -0.249642)
							(end -0.2794 -0.1778)
						)
						(arc
							(start -0.2794 0.1778)
							(mid -0.249642 0.249642)
							(end -0.1778 0.2794)
						)
						(arc
							(start 0.1778 0.2794)
							(mid 0.249642 0.249642)
							(end 0.2794 0.1778)
						)
						(arc
							(start 0.2794 -0.1778)
							(mid 0.249642 -0.249642)
							(end 0.1778 -0.2794)
						)
					)
					(width 0)
					(fill yes)
				)
			)
		)
		(pad "2" smd custom
			(at 0 0.4445 180)
			(size 0.1397 0.1397)
			(layers "F.Cu" "F.Mask" "F.Paste")
			(net "SW_PWR_R_HDD18")
			(options
				(clearance outline)
				(anchor circle)
			)
			(primitives
				(gr_poly
					(pts
						(arc
							(start -0.1778 -0.2794)
							(mid -0.249642 -0.249642)
							(end -0.2794 -0.1778)
						)
						(arc
							(start -0.2794 0.1778)
							(mid -0.249642 0.249642)
							(end -0.1778 0.2794)
						)
						(arc
							(start 0.1778 0.2794)
							(mid 0.249642 0.249642)
							(end 0.2794 0.1778)
						)
						(arc
							(start 0.2794 -0.1778)
							(mid 0.249642 -0.249642)
							(end 0.1778 -0.2794)
						)
					)
					(width 0)
					(fill yes)
				)
			)
		)
	)
	(footprint ""
		(layer "F.Cu")
		(at 239.798352 -134.393178 90)
		(property "Reference" "R371"
			(at 0 0 90)
			(layer "F.SilkS")
			(hide yes)
			(effects
				(font
					(size 1.27 1.27)
				)
			)
		)
		(property "Value" "10KR2F-2-GP"
			(at 0.064008 -3.993896 90)
			(unlocked yes)
			(layer "F.Fab")
			(hide yes)
			(effects
				(font
					(size 1.016 1.016)
					(thickness 0.1524)
				)
			)
		)
		(property "Device Type" "R402H16"
			(at 0.064008 -5.517896 90)
			(unlocked yes)
			(layer "F.Fab")
			(hide yes)
			(effects
				(font
					(size 1.016 1.016)
					(thickness 0.1524)
				)
			)
		)
		(duplicate_pad_numbers_are_jumpers no)
		(fp_line
			(start 0.508 -0.9398)
			(end -0.508 -0.9398)
			(stroke
				(width 0.1524)
				(type default)
			)
			(layer "F.SilkS")
		)
		(fp_line
			(start -0.508 -0.9398)
			(end -0.508 0.9398)
			(stroke
				(width 0.1524)
				(type default)
			)
			(layer "F.SilkS")
		)
		(fp_rect
			(start -0.508 0.9398)
			(end 0.508 -0.9398)
			(stroke
				(width 0)
				(type default)
			)
			(fill no)
			(layer "F.CrtYd")
		)
		(fp_rect
			(start -0.508 0.9398)
			(end 0.508 -0.9398)
			(stroke
				(width 0)
				(type default)
			)
			(fill no)
			(layer "F.Fab")
		)
		(pad "1" smd custom
			(at 0 -0.4445 90)
			(size 0.1397 0.1397)
			(layers "F.Cu" "F.Mask" "F.Paste")
			(net "P3V3_STBY_B")
			(options
				(clearance outline)
				(anchor circle)
			)
			(primitives
				(gr_poly
					(pts
						(arc
							(start -0.1778 -0.2794)
							(mid -0.249642 -0.249642)
							(end -0.2794 -0.1778)
						)
						(arc
							(start -0.2794 0.1778)
							(mid -0.249642 0.249642)
							(end -0.1778 0.2794)
						)
						(arc
							(start 0.1778 0.2794)
							(mid 0.249642 0.249642)
							(end 0.2794 0.1778)
						)
						(arc
							(start 0.2794 -0.1778)
							(mid 0.249642 -0.249642)
							(end 0.1778 -0.2794)
						)
					)
					(width 0)
					(fill yes)
				)
			)
		)
		(pad "2" smd custom
			(at 0 0.4445 90)
			(size 0.1397 0.1397)
			(layers "F.Cu" "F.Mask" "F.Paste")
			(net "I2C_DPB_BUFF_EN")
			(options
				(clearance outline)
				(anchor circle)
			)
			(primitives
				(gr_poly
					(pts
						(arc
							(start -0.1778 -0.2794)
							(mid -0.249642 -0.249642)
							(end -0.2794 -0.1778)
						)
						(arc
							(start -0.2794 0.1778)
							(mid -0.249642 0.249642)
							(end -0.1778 0.2794)
						)
						(arc
							(start 0.1778 0.2794)
							(mid 0.249642 0.249642)
							(end 0.2794 0.1778)
						)
						(arc
							(start 0.2794 -0.1778)
							(mid 0.249642 -0.249642)
							(end 0.1778 -0.2794)
						)
					)
					(width 0)
					(fill yes)
				)
			)
		)
	)
	(footprint ""
		(layer "F.Cu")
		(at 471.805 -254.127 -90)
		(property "Reference" "C181"
			(at 0 0 270)
			(layer "F.SilkS")
			(hide yes)
			(effects
				(font
					(size 1.27 1.27)
				)
			)
		)
		(property "Value" "SCD033U25V2KX-GP"
			(at 1.1811 -2.7051 270)
			(unlocked yes)
			(layer "F.Fab")
			(hide yes)
			(effects
				(font
					(size 1.016 1.016)
					(thickness 0.1524)
				)
			)
		)
		(property "Device Type" "C402H22"
			(at 1.1811 -4.2291 270)
			(unlocked yes)
			(layer "F.Fab")
			(hide yes)
			(effects
				(font
					(size 1.016 1.016)
					(thickness 0.1524)
				)
			)
		)
		(duplicate_pad_numbers_are_jumpers no)
		(fp_rect
			(start -0.4318 0.9525)
			(end 0.4318 -0.9525)
			(stroke
				(width 0)
				(type default)
			)
			(fill no)
			(layer "F.CrtYd")
		)
		(fp_rect
			(start -0.4318 0.9525)
			(end 0.4318 -0.9525)
			(stroke
				(width 0)
				(type default)
			)
			(fill no)
			(layer "F.Fab")
		)
		(pad "1" smd custom
			(at 0 -0.4445 270)
			(size 0.1524 0.1524)
			(layers "F.Cu" "F.Mask" "F.Paste")
			(net "SW_HDD_P11")
			(options
				(clearance outline)
				(anchor circle)
			)
			(primitives
				(gr_poly
					(pts
						(arc
							(start 0.3048 -0.2032)
							(mid 0.275042 -0.275042)
							(end 0.2032 -0.3048)
						)
						(arc
							(start -0.2032 -0.3048)
							(mid -0.275042 -0.275042)
							(end -0.3048 -0.2032)
						)
						(arc
							(start -0.3048 0.2032)
							(mid -0.275042 0.275042)
							(end -0.2032 0.3048)
						)
						(arc
							(start 0.2032 0.3048)
							(mid 0.275042 0.275042)
							(end 0.3048 0.2032)
						)
					)
					(width 0)
					(fill yes)
				)
			)
		)
		(pad "2" smd custom
			(at 0 0.4445 270)
			(size 0.1524 0.1524)
			(layers "F.Cu" "F.Mask" "F.Paste")
			(net "GND")
			(options
				(clearance outline)
				(anchor circle)
			)
			(primitives
				(gr_poly
					(pts
						(arc
							(start 0.3048 -0.2032)
							(mid 0.275042 -0.275042)
							(end 0.2032 -0.3048)
						)
						(arc
							(start -0.2032 -0.3048)
							(mid -0.275042 -0.275042)
							(end -0.3048 -0.2032)
						)
						(arc
							(start -0.3048 0.2032)
							(mid -0.275042 0.275042)
							(end -0.2032 0.3048)
						)
						(arc
							(start 0.2032 0.3048)
							(mid 0.275042 0.275042)
							(end 0.3048 0.2032)
						)
					)
					(width 0)
					(fill yes)
				)
			)
		)
	)
	(footprint ""
		(layer "F.Cu")
		(at 426.72 -13.589)
		(property "Reference" "R841"
			(at 0 0 0)
			(layer "F.SilkS")
			(hide yes)
			(effects
				(font
					(size 1.27 1.27)
				)
			)
		)
		(property "Value" "4K7R2F-GP"
			(at 0.064008 -3.993896 0)
			(unlocked yes)
			(layer "F.Fab")
			(hide yes)
			(effects
				(font
					(size 1.016 1.016)
					(thickness 0.1524)
				)
			)
		)
		(property "Device Type" "R402H16"
			(at 0.064008 -5.517896 0)
			(unlocked yes)
			(layer "F.Fab")
			(hide yes)
			(effects
				(font
					(size 1.016 1.016)
					(thickness 0.1524)
				)
			)
		)
		(duplicate_pad_numbers_are_jumpers no)
		(fp_line
			(start -0.508 -0.9398)
			(end -0.508 0.9398)
			(stroke
				(width 0.1524)
				(type default)
			)
			(layer "F.SilkS")
		)
		(fp_line
			(start 0.508 -0.9398)
			(end -0.508 -0.9398)
			(stroke
				(width 0.1524)
				(type default)
			)
			(layer "F.SilkS")
		)
		(fp_rect
			(start -0.508 0.9398)
			(end 0.508 -0.9398)
			(stroke
				(width 0)
				(type default)
			)
			(fill no)
			(layer "F.CrtYd")
		)
		(fp_rect
			(start -0.508 0.9398)
			(end 0.508 -0.9398)
			(stroke
				(width 0)
				(type default)
			)
			(fill no)
			(layer "F.Fab")
		)
		(pad "1" smd custom
			(at 0 -0.4445)
			(size 0.1397 0.1397)
			(layers "F.Cu" "F.Mask" "F.Paste")
			(net "SW_PWR_R_HDD33")
			(options
				(clearance outline)
				(anchor circle)
			)
			(primitives
				(gr_poly
					(pts
						(arc
							(start -0.1778 -0.2794)
							(mid -0.249642 -0.249642)
							(end -0.2794 -0.1778)
						)
						(arc
							(start -0.2794 0.1778)
							(mid -0.249642 0.249642)
							(end -0.1778 0.2794)
						)
						(arc
							(start 0.1778 0.2794)
							(mid 0.249642 0.249642)
							(end 0.2794 0.1778)
						)
						(arc
							(start 0.2794 -0.1778)
							(mid 0.249642 -0.249642)
							(end 0.1778 -0.2794)
						)
					)
					(width 0)
					(fill yes)
				)
			)
		)
		(pad "2" smd custom
			(at 0 0.4445)
			(size 0.1397 0.1397)
			(layers "F.Cu" "F.Mask" "F.Paste")
			(net "GND")
			(options
				(clearance outline)
				(anchor circle)
			)
			(primitives
				(gr_poly
					(pts
						(arc
							(start -0.1778 -0.2794)
							(mid -0.249642 -0.249642)
							(end -0.2794 -0.1778)
						)
						(arc
							(start -0.2794 0.1778)
							(mid -0.249642 0.249642)
							(end -0.1778 0.2794)
						)
						(arc
							(start 0.1778 0.2794)
							(mid 0.249642 0.249642)
							(end 0.2794 0.1778)
						)
						(arc
							(start 0.2794 -0.1778)
							(mid 0.249642 -0.249642)
							(end 0.1778 -0.2794)
						)
					)
					(width 0)
					(fill yes)
				)
			)
		)
	)
	(footprint ""
		(layer "F.Cu")
		(at 141.097 -139.446 -90)
		(property "Reference" "R453"
			(at 0 0 270)
			(layer "F.SilkS")
			(hide yes)
			(effects
				(font
					(size 1.27 1.27)
				)
			)
		)
		(property "Value" "300KR2F-GP"
			(at 0.064008 -3.993896 270)
			(unlocked yes)
			(layer "F.Fab")
			(hide yes)
			(effects
				(font
					(size 1.016 1.016)
					(thickness 0.1524)
				)
			)
		)
		(property "Device Type" "R402H16"
			(at 0.064008 -5.517896 270)
			(unlocked yes)
			(layer "F.Fab")
			(hide yes)
			(effects
				(font
					(size 1.016 1.016)
					(thickness 0.1524)
				)
			)
		)
		(duplicate_pad_numbers_are_jumpers no)
		(fp_line
			(start -0.508 -0.9398)
			(end -0.508 0.9398)
			(stroke
				(width 0.1524)
				(type default)
			)
			(layer "F.SilkS")
		)
		(fp_line
			(start 0.508 -0.9398)
			(end -0.508 -0.9398)
			(stroke
				(width 0.1524)
				(type default)
			)
			(layer "F.SilkS")
		)
		(fp_rect
			(start -0.508 0.9398)
			(end 0.508 -0.9398)
			(stroke
				(width 0)
				(type default)
			)
			(fill no)
			(layer "F.CrtYd")
		)
		(fp_rect
			(start -0.508 0.9398)
			(end 0.508 -0.9398)
			(stroke
				(width 0)
				(type default)
			)
			(fill no)
			(layer "F.Fab")
		)
		(pad "1" smd custom
			(at 0 -0.4445 270)
			(size 0.1397 0.1397)
			(layers "F.Cu" "F.Mask" "F.Paste")
			(net "SW_HDD_N16")
			(options
				(clearance outline)
				(anchor circle)
			)
			(primitives
				(gr_poly
					(pts
						(arc
							(start -0.1778 -0.2794)
							(mid -0.249642 -0.249642)
							(end -0.2794 -0.1778)
						)
						(arc
							(start -0.2794 0.1778)
							(mid -0.249642 0.249642)
							(end -0.1778 0.2794)
						)
						(arc
							(start 0.1778 0.2794)
							(mid 0.249642 0.249642)
							(end 0.2794 0.1778)
						)
						(arc
							(start 0.2794 -0.1778)
							(mid 0.249642 -0.249642)
							(end 0.1778 -0.2794)
						)
					)
					(width 0)
					(fill yes)
				)
			)
		)
		(pad "2" smd custom
			(at 0 0.4445 270)
			(size 0.1397 0.1397)
			(layers "F.Cu" "F.Mask" "F.Paste")
			(net "P12V_B")
			(options
				(clearance outline)
				(anchor circle)
			)
			(primitives
				(gr_poly
					(pts
						(arc
							(start -0.1778 -0.2794)
							(mid -0.249642 -0.249642)
							(end -0.2794 -0.1778)
						)
						(arc
							(start -0.2794 0.1778)
							(mid -0.249642 0.249642)
							(end -0.1778 0.2794)
						)
						(arc
							(start 0.1778 0.2794)
							(mid 0.249642 0.249642)
							(end 0.2794 0.1778)
						)
						(arc
							(start 0.2794 -0.1778)
							(mid 0.249642 -0.249642)
							(end 0.1778 -0.2794)
						)
					)
					(width 0)
					(fill yes)
				)
			)
		)
	)
	(footprint ""
		(layer "F.Cu")
		(at 105.992168 -97.328228 -90)
		(property "Reference" "R388"
			(at 0 0 270)
			(layer "F.SilkS")
			(hide yes)
			(effects
				(font
					(size 1.27 1.27)
				)
			)
		)
		(property "Value" "4K7R2F-GP"
			(at 0.064008 -3.993896 270)
			(unlocked yes)
			(layer "F.Fab")
			(hide yes)
			(effects
				(font
					(size 1.016 1.016)
					(thickness 0.1524)
				)
			)
		)
		(property "Device Type" "R402H16"
			(at 0.064008 -5.517896 270)
			(unlocked yes)
			(layer "F.Fab")
			(hide yes)
			(effects
				(font
					(size 1.016 1.016)
					(thickness 0.1524)
				)
			)
		)
		(duplicate_pad_numbers_are_jumpers no)
		(fp_line
			(start -0.508 -0.9398)
			(end -0.508 0.9398)
			(stroke
				(width 0.1524)
				(type default)
			)
			(layer "F.SilkS")
		)
		(fp_line
			(start 0.508 -0.9398)
			(end -0.508 -0.9398)
			(stroke
				(width 0.1524)
				(type default)
			)
			(layer "F.SilkS")
		)
		(fp_rect
			(start -0.508 0.9398)
			(end 0.508 -0.9398)
			(stroke
				(width 0)
				(type default)
			)
			(fill no)
			(layer "F.CrtYd")
		)
		(fp_rect
			(start -0.508 0.9398)
			(end 0.508 -0.9398)
			(stroke
				(width 0)
				(type default)
			)
			(fill no)
			(layer "F.Fab")
		)
		(pad "1" smd custom
			(at 0 -0.4445 270)
			(size 0.1397 0.1397)
			(layers "F.Cu" "F.Mask" "F.Paste")
			(net "DRIVE_B_15_ACT")
			(options
				(clearance outline)
				(anchor circle)
			)
			(primitives
				(gr_poly
					(pts
						(arc
							(start -0.1778 -0.2794)
							(mid -0.249642 -0.249642)
							(end -0.2794 -0.1778)
						)
						(arc
							(start -0.2794 0.1778)
							(mid -0.249642 0.249642)
							(end -0.1778 0.2794)
						)
						(arc
							(start 0.1778 0.2794)
							(mid 0.249642 0.249642)
							(end 0.2794 0.1778)
						)
						(arc
							(start 0.2794 -0.1778)
							(mid 0.249642 -0.249642)
							(end 0.1778 -0.2794)
						)
					)
					(width 0)
					(fill yes)
				)
			)
		)
		(pad "2" smd custom
			(at 0 0.4445 270)
			(size 0.1397 0.1397)
			(layers "F.Cu" "F.Mask" "F.Paste")
			(net "GND")
			(options
				(clearance outline)
				(anchor circle)
			)
			(primitives
				(gr_poly
					(pts
						(arc
							(start -0.1778 -0.2794)
							(mid -0.249642 -0.249642)
							(end -0.2794 -0.1778)
						)
						(arc
							(start -0.2794 0.1778)
							(mid -0.249642 0.249642)
							(end -0.1778 0.2794)
						)
						(arc
							(start 0.1778 0.2794)
							(mid 0.249642 0.249642)
							(end 0.2794 0.1778)
						)
						(arc
							(start 0.2794 -0.1778)
							(mid 0.249642 -0.249642)
							(end 0.1778 -0.2794)
						)
					)
					(width 0)
					(fill yes)
				)
			)
		)
	)
)
